# T6G (Grand Teton) — schematic parts with pin connectivity, parts 2601–2601 of 8303; source: Cadence DE-HDL packaged netlist (pstxprt.dat, pstxnet.dat, pstchip.dat)

J19  SCONN288_DDR506112002KQ  IO  pkg DDR288S_1-1VXC  page 89
  1  VIN_BULK0  POWER  = P12V_MEM_CPU0
  2  RFU0  TRI  = NC
  3  VIN_MGMT  POWER  = P3V3_AUX
  4  HSCL  IN  = I3C_SPD_DDRD_CPU0_SCL
  5  HSDA  BI  = I3C_SPD_DDRD_CPU0_SDA
  6  VSS0  POWER  = GND
  7  DQ0_A  BI  = M_D_CPU0_SA_DQ<0>
  8  VSS1  POWER  = GND
  9  DQ1_A  BI  = M_D_CPU0_SA_DQ<1>
  10  VSS2  POWER  = GND
  11  DQS0_A_T  BI  = M_D_CPU0_SA_DQS_DP<0>
  12  DQS0_A_C  BI  = M_D_CPU0_SA_DQS_DN<0>
  13  VSS3  POWER  = GND
  14  DQ4_A  BI  = M_D_CPU0_SA_DQ<4>
  15  VSS4  POWER  = GND
  16  DQ5_A  BI  = M_D_CPU0_SA_DQ<5>
  17  VSS5  POWER  = GND
  18  DQ8_A  BI  = M_D_CPU0_SA_DQ<8>
  19  VSS6  POWER  = GND
  20  DQ9_A  BI  = M_D_CPU0_SA_DQ<9>
  21  VSS7  POWER  = GND
  22  DQS1_A_T  BI  = M_D_CPU0_SA_DQS_DP<1>
  23  DQS1_A_C  BI  = M_D_CPU0_SA_DQS_DN<1>
  24  VSS8  POWER  = GND
  25  DQ12_A  BI  = M_D_CPU0_SA_DQ<12>
  26  VSS9  POWER  = GND
  27  DQ13_A  BI  = M_D_CPU0_SA_DQ<13>
  28  VSS10  POWER  = GND
  29  DQ16_A  BI  = M_D_CPU0_SA_DQ<16>
  30  VSS11  POWER  = GND
  31  DQ17_A  BI  = M_D_CPU0_SA_DQ<17>
  32  VSS12  POWER  = GND
  33  DQS2_A_T  BI  = M_D_CPU0_SA_DQS_DP<2>
  34  DQS2_A_C  BI  = M_D_CPU0_SA_DQS_DN<2>
  35  VSS13  POWER  = GND
  36  DQ20_A  BI  = M_D_CPU0_SA_DQ<20>
  37  VSS14  POWER  = GND
  38  DQ21_A  BI  = M_D_CPU0_SA_DQ<21>
  39  VSS15  POWER  = GND
  40  DQ24_A  BI  = M_D_CPU0_SA_DQ<24>
  41  VSS16  POWER  = GND
  42  DQ25_A  BI  = M_D_CPU0_SA_DQ<25>
  43  VSS17  POWER  = GND
  44  DQS3_A_T  BI  = M_D_CPU0_SA_DQS_DP<3>
  45  DQS3_A_C  BI  = M_D_CPU0_SA_DQS_DN<3>
  46  VSS18  POWER  = GND
  47  DQ28_A  BI  = M_D_CPU0_SA_DQ<28>
  48  VSS19  POWER  = GND
  49  DQ29_A  BI  = M_D_CPU0_SA_DQ<29>
  50  VSS20  POWER  = GND
  51  CB0_A  BI  = M_D_CPU0_SA_CB<0>
  52  VSS21  POWER  = GND
  53  CB1_A  BI  = M_D_CPU0_SA_CB<1>
  54  VSS22  POWER  = GND
  55  DQS4_A_T  BI  = M_D_CPU0_SA_DQS_DP<4>
  56  DQS4_A_C  BI  = M_D_CPU0_SA_DQS_DN<4>
  57  VSS23  POWER  = GND
  58  CB4_A  BI  = M_D_CPU0_SA_CB<4>
  59  VSS24  POWER  = GND
  60  CB5_A  BI  = M_D_CPU0_SA_CB<5>
  61  VSS25  POWER  = GND
  62  ALERT_N  OUT  = M_D_CPU0_ALERT_N
  63  VSS26  POWER  = GND
  64  CS0_A_N  IN  = M_D_CPU0_SA_CS_N<0>
  65  VSS27  POWER  = GND
  66  CA0_A  IN  = M_D_CPU0_SA_CA<0>
  67  VSS28  POWER  = GND
  68  CA2_A  IN  = M_D_CPU0_SA_CA<2>
  69  VSS29  POWER  = GND
  70  CA4_A  IN  = M_D_CPU0_SA_CA<4>
  71  VSS30  POWER  = GND
  72  CA6_A  IN  = M_D_CPU0_SA_CA<6>
  73  VSS31  POWER  = GND
  74  PAR_A  IN  = M_D_CPU0_SA_PAR
  75  VSS32  POWER  = GND
  76  CA0_B  IN  = M_D_CPU0_SB_CA<0>
  77  VSS33  POWER  = GND
  78  CA2_B  IN  = M_D_CPU0_SB_CA<2>
  79  VSS34  POWER  = GND
  80  CA4_B  IN  = M_D_CPU0_SB_CA<4>
  81  VSS35  POWER  = GND
  82  CA6_B  IN  = M_D_CPU0_SB_CA<6>
  83  VSS36  POWER  = GND
  84  CS0_B_N  IN  = M_D_CPU0_SB_CS_N<0>
  85  VSS37  POWER  = GND
  86  \lbd||rsp_a_n\  OUT  = M_D_CPU0_SA_RSP<0>
  87  \lbs||rsp_b_n\  OUT  = M_D_CPU0_SB_RSP<0>
  88  VSS38  POWER  = GND
  89  CB4_B  BI  = M_D_CPU0_SB_CB<4>
  90  VSS39  POWER  = GND
  91  CB5_B  BI  = M_D_CPU0_SB_CB<5>
  92  VSS40  POWER  = GND
  93  \dqs9_b_t||tdqs9_b_t||dbi4_b_n\  BI  = M_D_CPU0_SB_DQS_DP<9>
  94  \dqs9_b_c||tdqs9_b_c\  BI  = M_D_CPU0_SB_DQS_DN<9>
  95  VSS41  POWER  = GND
  96  CB0_B  BI  = M_D_CPU0_SB_CB<0>
  97  VSS42  POWER  = GND
  98  CB1_B  BI  = M_D_CPU0_SB_CB<1>
  99  VSS43  POWER  = GND
  100  DQ0_B  BI  = M_D_CPU0_SB_DQ<0>
  101  VSS44  POWER  = GND
  102  DQ1_B  BI  = M_D_CPU0_SB_DQ<1>
  103  VSS45  POWER  = GND
  104  DQS0_B_T  BI  = M_D_CPU0_SB_DQS_DP<0>
  105  DQS0_B_C  BI  = M_D_CPU0_SB_DQS_DN<0>
  106  VSS46  POWER  = GND
  107  DQ4_B  BI  = M_D_CPU0_SB_DQ<4>
  108  VSS47  POWER  = GND
  109  DQ5_B  BI  = M_D_CPU0_SB_DQ<5>
  110  VSS48  POWER  = GND
  111  DQ8_B  BI  = M_D_CPU0_SB_DQ<8>
  112  VSS49  POWER  = GND
  113  DQ9_B  BI  = M_D_CPU0_SB_DQ<9>
  114  VSS50  POWER  = GND
  115  DQS1_B_T  BI  = M_D_CPU0_SB_DQS_DP<1>
  116  DQS1_B_C  BI  = M_D_CPU0_SB_DQS_DN<1>
  117  VSS51  POWER  = GND
  118  DQ12_B  BI  = M_D_CPU0_SB_DQ<12>
  119  VSS52  POWER  = GND
  120  DQ13_B  BI  = M_D_CPU0_SB_DQ<13>
  121  VSS53  POWER  = GND
  122  DQ16_B  BI  = M_D_CPU0_SB_DQ<16>
  123  VSS54  POWER  = GND
  124  DQ17_B  BI  = M_D_CPU0_SB_DQ<17>
  125  VSS55  POWER  = GND
  126  DQS2_B_T  BI  = M_D_CPU0_SB_DQS_DP<2>
  127  DQS2_B_C  BI  = M_D_CPU0_SB_DQS_DN<2>
  128  VSS56  POWER  = GND
  129  DQ20_B  BI  = M_D_CPU0_SB_DQ<20>
  130  VSS57  POWER  = GND
  131  DQ21_B  BI  = M_D_CPU0_SB_DQ<21>
  132  VSS58  POWER  = GND
  133  DQ24_B  BI  = M_D_CPU0_SB_DQ<24>
  134  VSS59  POWER  = GND
  135  DQ25_B  BI  = M_D_CPU0_SB_DQ<25>
  136  VSS60  POWER  = GND
  137  DQS3_B_T  BI  = M_D_CPU0_SB_DQS_DP<3>
  138  DQS3_B_C  BI  = M_D_CPU0_SB_DQS_DN<3>
  139  VSS61  POWER  = GND
  140  DQ28_B  BI  = M_D_CPU0_SB_DQ<28>
  141  VSS62  POWER  = GND
  142  DQ29_B  BI  = M_D_CPU0_SB_DQ<29>
  143  VSS63  POWER  = GND
  144  RFU1  TRI  = NC
  145  VIN_BULK1  POWER  = P12V_MEM_CPU0
  146  VIN_BULK2  POWER  = P12V_MEM_CPU0
  147  \pwr_good||fail_n\  BI  = PWRGD_CHD_CPU0_DIMM
  148  HAS  IN  = PD_CHD_CPU0_DIMM_SAA
  149  RFU2  TRI  = NC
  150  RFU3  TRI  = NC
  151  VSS64  POWER  = GND
  152  DQ2_A  BI  = M_D_CPU0_SA_DQ<2>
  153  VSS65  POWER  = GND
  154  DQ3_A  BI  = M_D_CPU0_SA_DQ<3>
  155  VSS66  POWER  = GND
  156  \dqs5_a_c||tdqs5_a_c||dqs5_a_t||tdqs5_a_t\  BI  = M_D_CPU0_SA_DQS_DN<5>
  157  \dqs5_a_t||tdqs5_a_t\  BI  = M_D_CPU0_SA_DQS_DP<5>
  158  VSS67  POWER  = GND
  159  DQ6_A  BI  = M_D_CPU0_SA_DQ<6>
  160  VSS68  POWER  = GND
  161  DQ7_A  BI  = M_D_CPU0_SA_DQ<7>
  162  VSS69  POWER  = GND
  163  DQ10_A  BI  = M_D_CPU0_SA_DQ<10>
  164  VSS70  POWER  = GND
  165  DQ11_A  BI  = M_D_CPU0_SA_DQ<11>
  166  VSS71  POWER  = GND
  167  \dqs6_a_c||tdqs6_a_c||dqs6_a_t||tdqs6_a_t\  BI  = M_D_CPU0_SA_DQS_DN<6>
  168  \dqs6_a_t||tdqs6_a_t\  BI  = M_D_CPU0_SA_DQS_DP<6>
  169  VSS72  POWER  = GND
  170  DQ14_A  BI  = M_D_CPU0_SA_DQ<14>
  171  VSS73  POWER  = GND
  172  DQ15_A  BI  = M_D_CPU0_SA_DQ<15>
  173  VSS74  POWER  = GND
  174  DQ18_A  BI  = M_D_CPU0_SA_DQ<18>
  175  VSS75  POWER  = GND
  176  DQ19_A  BI  = M_D_CPU0_SA_DQ<19>
  177  VSS76  POWER  = GND
  178  \dqs7_a_c||tdqs7_a_c\  BI  = M_D_CPU0_SA_DQS_DN<7>
  179  \dqs7_a_t||tdqs7_a_t\  BI  = M_D_CPU0_SA_DQS_DP<7>
  180  VSS77  POWER  = GND
  181  DQ22_A  BI  = M_D_CPU0_SA_DQ<22>
  182  VSS78  POWER  = GND
  183  DQ23_A  BI  = M_D_CPU0_SA_DQ<23>
  184  VSS79  POWER  = GND
  185  DQ26_A  BI  = M_D_CPU0_SA_DQ<26>
  186  VSS80  POWER  = GND
  187  DQ27_A  BI  = M_D_CPU0_SA_DQ<27>
  188  VSS81  POWER  = GND
  189  \dqs8_a_c||tdqs8_a_c\  BI  = M_D_CPU0_SA_DQS_DN<8>
  190  \dqs8_a_t||tdqs8_a_t\  BI  = M_D_CPU0_SA_DQS_DP<8>
  191  VSS82  POWER  = GND
  192  DQ30_A  BI  = M_D_CPU0_SA_DQ<30>
  193  VSS83  POWER  = GND
  194  DQ31_A  BI  = M_D_CPU0_SA_DQ<31>
  195  VSS84  POWER  = GND
  196  CB2_A  BI  = M_D_CPU0_SA_CB<2>
  197  VSS85  POWER  = GND
  198  CB3_A  BI  = M_D_CPU0_SA_CB<3>
  199  VSS86  POWER  = GND
  200  \dqs9_a_c||tdqs9_a_c\  BI  = M_D_CPU0_SA_DQS_DN<9>
  201  \dqs9_a_t||tdqs9_a_t\  BI  = M_D_CPU0_SA_DQS_DP<9>
  202  VSS87  POWER  = GND
  203  CB6_A  BI  = M_D_CPU0_SA_CB<6>
  204  VSS88  POWER  = GND
  205  CB7_A  BI  = M_D_CPU0_SA_CB<7>
  206  VSS89  POWER  = GND
  207  RESET_N  IN  = M_D_CPU0_RESET_N
  208  VSS90  POWER  = GND
  209  CS1_A_N  IN  = M_D_CPU0_SA_CS_N<1>
  210  VSS91  POWER  = GND
  211  CA1_A  IN  = M_D_CPU0_SA_CA<1>
  212  VSS92  POWER  = GND
  213  CA3_A  IN  = M_D_CPU0_SA_CA<3>
  214  VSS93  POWER  = GND
  215  CA5_A  IN  = M_D_CPU0_SA_CA<5>
  216  VSS94  POWER  = GND
  217  CK_T  IN  = M_D_CPU0_CLK_DP<0>
  218  CK_C  IN  = M_D_CPU0_CLK_DN<0>
  219  VSS95  POWER  = GND
  220  RFU4  TRI  = NC
  221  CA1_B  IN  = M_D_CPU0_SB_CA<1>
  222  VSS96  POWER  = GND
  223  CA3_B  IN  = M_D_CPU0_SB_CA<3>
  224  VSS97  POWER  = GND
  225  CA5_B  IN  = M_D_CPU0_SB_CA<5>
  226  VSS98  POWER  = GND
  227  PAR_B  IN  = M_D_CPU0_SB_PAR
  228  VSS99  POWER  = GND
  229  CS1_B_N  IN  = M_D_CPU0_SB_CS_N<1>
  230  VSS100  POWER  = GND
  231  RFU5  TRI  = NC
  232  RFU6  TRI  = NC
  233  VSS101  POWER  = GND
  234  CB6_B  BI  = M_D_CPU0_SB_CB<6>
  235  VSS102  POWER  = GND
  236  CB7_B  BI  = M_D_CPU0_SB_CB<7>
  237  VSS103  POWER  = GND
  238  DQS4_B_C  BI  = M_D_CPU0_SB_DQS_DN<4>
  239  DQS4_B_T  BI  = M_D_CPU0_SB_DQS_DP<4>
  240  VSS104  POWER  = GND
  241  CB2_B  BI  = M_D_CPU0_SB_CB<2>
  242  VSS105  POWER  = GND
  243  CB3_B  BI  = M_D_CPU0_SB_CB<3>
  244  VSS106  POWER  = GND
  245  DQ2_B  BI  = M_D_CPU0_SB_DQ<2>
  246  VSS107  POWER  = GND
  247  DQ3_B  BI  = M_D_CPU0_SB_DQ<3>
  248  VSS108  POWER  = GND
  249  \dqs5_b_c||tdqs5_b_c\  BI  = M_D_CPU0_SB_DQS_DN<5>
  250  \dqs5_b_t||tdqs5_b_t\  BI  = M_D_CPU0_SB_DQS_DP<5>
  251  VSS109  POWER  = GND
  252  DQ6_B  BI  = M_D_CPU0_SB_DQ<6>
  253  VSS110  POWER  = GND
  254  DQ7_B  BI  = M_D_CPU0_SB_DQ<7>
  255  VSS111  POWER  = GND
  256  DQ10_B  BI  = M_D_CPU0_SB_DQ<10>
  257  VSS112  POWER  = GND
  258  DQ11_B  BI  = M_D_CPU0_SB_DQ<11>
  259  VSS113  POWER  = GND
  260  \dqs6_b_c||tdqs6_b_c\  BI  = M_D_CPU0_SB_DQS_DN<6>
  261  \dqs6_b_t||tdqs6_b_t\  BI  = M_D_CPU0_SB_DQS_DP<6>
  262  VSS114  POWER  = GND
  263  DQ14_B  BI  = M_D_CPU0_SB_DQ<14>
  264  VSS115  POWER  = GND
  265  DQ15_B  BI  = M_D_CPU0_SB_DQ<15>
  266  VSS116  POWER  = GND
  267  DQ18_B  BI  = M_D_CPU0_SB_DQ<18>
  268  VSS117  POWER  = GND
  269  DQ19_B  BI  = M_D_CPU0_SB_DQ<19>
  270  VSS118  POWER  = GND
  271  \dqs7_b_c||tdqs7_b_c\  BI  = M_D_CPU0_SB_DQS_DN<7>
  272  \dqs7_b_t||tdqs7_b_t\  BI  = M_D_CPU0_SB_DQS_DP<7>
  273  VSS119  POWER  = GND
  274  DQ22_B  BI  = M_D_CPU0_SB_DQ<22>
  275  VSS120  POWER  = GND
  276  DQ23_B  BI  = M_D_CPU0_SB_DQ<23>
  277  VSS121  POWER  = GND
  278  DQ26_B  BI  = M_D_CPU0_SB_DQ<26>
  279  VSS122  POWER  = GND
  280  DQ27_B  BI  = M_D_CPU0_SB_DQ<27>
  281  VSS123  POWER  = GND
  282  \dqs8_b_c||tdqs8_b_c\  BI  = M_D_CPU0_SB_DQS_DN<8>
  283  \dqs8_b_t||tdqs8_b_t\  BI  = M_D_CPU0_SB_DQS_DP<8>
  284  VSS124  POWER  = GND
  285  DQ30_B  BI  = M_D_CPU0_SB_DQ<30>
  286  VSS125  POWER  = GND
  287  DQ31_B  BI  = M_D_CPU0_SB_DQ<31>
  288  VSS126  POWER  = GND
  G1  G1  POWER  = GND
  G2  G2  POWER  = GND
  G3  G3  POWER  = GND
